(kicad_pcb
	(version 20241229)
	(generator "pcbnew")
	(generator_version "9.0")
	(general
		(thickness 1.599998)
		(legacy_teardrops no)
	)
	(paper "A4")
	(title_block
		(date "2023-02-12")
		(rev "1.1.5")
		(comment 9 "footprints 203-209 of 473")
	)
	(layers
		(0 "F.Cu" signal)
		(4 "In1.Cu" power "In1.GND")
		(6 "In2.Cu" signal)
		(8 "In3.Cu" power "In3.GND")
		(10 "In4.Cu" power "In4.VCC")
		(12 "In5.Cu" signal)
		(14 "In6.Cu" power "In6.VCC")
		(2 "B.Cu" signal)
		(9 "F.Adhes" user "F.Adhesive")
		(11 "B.Adhes" user "B.Adhesive")
		(13 "F.Paste" user)
		(15 "B.Paste" user)
		(5 "F.SilkS" user "F.Silkscreen")
		(7 "B.SilkS" user "B.Silkscreen")
		(1 "F.Mask" user)
		(3 "B.Mask" user)
		(17 "Dwgs.User" user "User.Drawings")
		(19 "Cmts.User" user "User.Comments")
		(21 "Eco1.User" user "User.Eco1")
		(23 "Eco2.User" user "User.Eco2")
		(25 "Edge.Cuts" user)
		(27 "Margin" user)
		(31 "F.CrtYd" user "F.Courtyard")
		(29 "B.CrtYd" user "B.Courtyard")
		(35 "F.Fab" user)
		(33 "B.Fab" user)
	)
	(footprint "antmicro-footprints:TP_SMD_1mm"
		(layer "F.Cu")
		(at 124.3492 106.6)
		(property "Reference" "TP13"
			(at 0.5508 0.3 0)
			(layer "F.SilkS")
			(effects
				(font
					(size 0.7 0.7)
					(thickness 0.15)
				)
				(justify left bottom)
			)
		)
		(property "Value" "TP_1mm_SMD"
			(at 0 1.4 0)
			(layer "F.Fab")
			(effects
				(font
					(size 0.7 0.7)
					(thickness 0.15)
				)
				(justify left bottom)
			)
		)
		(property "Description" "Test Point 1mm"
			(at 0 0 0)
			(layer "F.Fab")
			(hide yes)
			(effects
				(font
					(size 1.27 1.27)
					(thickness 0.15)
				)
			)
		)
		(property "Author" "Antmicro"
			(at 0 0 0)
			(layer "F.Fab")
			(hide yes)
			(effects
				(font
					(size 1 1)
					(thickness 0.15)
				)
			)
		)
		(property "License" "Apache-2.0"
			(at 0 0 0)
			(layer "F.Fab")
			(hide yes)
			(effects
				(font
					(size 1 1)
					(thickness 0.15)
				)
			)
		)
		(property "MPN" ""
			(at 0 0 0)
			(layer "F.Fab")
			(hide yes)
			(effects
				(font
					(size 1 1)
					(thickness 0.15)
				)
			)
		)
		(property "Manufacturer" ""
			(at 0 0 0)
			(layer "F.Fab")
			(hide yes)
			(effects
				(font
					(size 1 1)
					(thickness 0.15)
				)
			)
		)
		(sheetname "Supply")
		(sheetfile "supply.kicad_sch")
		(attr exclude_from_pos_files)
		(pad "1" smd circle
			(at 0 0)
			(size 1 1)
			(layers "F.Cu" "F.Mask")
			(net 463 "VCC5V0_INT")
			(pinfunction "1")
			(pintype "passive")
		)
	)
	(footprint "antmicro-footprints:C_0402_1005Metric"
		(layer "F.Cu")
		(at 111.725 96.249 180)
		(descr "Capacitor SMD 0402")
		(tags "capacitor SMD 0402")
		(property "Reference" "C167"
			(at 3.625 -0.351 180)
			(layer "F.SilkS")
			(effects
				(font
					(size 0.7 0.7)
					(thickness 0.15)
				)
				(justify left bottom)
			)
		)
		(property "Value" "C_22u_0402"
			(at 0 1.4 180)
			(layer "F.Fab")
			(effects
				(font
					(size 0.7 0.7)
					(thickness 0.15)
				)
				(justify left bottom)
			)
		)
		(property "Description" " "
			(at 0 0 180)
			(layer "F.Fab")
			(hide yes)
			(effects
				(font
					(size 1.27 1.27)
					(thickness 0.15)
				)
			)
		)
		(property "Author" "Antmicro"
			(at 223.45 192.498 0)
			(layer "F.Fab")
			(hide yes)
			(effects
				(font
					(size 1 1)
					(thickness 0.15)
				)
			)
		)
		(property "Dielectric" ""
			(at 223.45 192.498 0)
			(layer "F.Fab")
			(hide yes)
			(effects
				(font
					(size 1 1)
					(thickness 0.15)
				)
			)
		)
		(property "License" "Apache-2.0"
			(at 223.45 192.498 0)
			(layer "F.Fab")
			(hide yes)
			(effects
				(font
					(size 1 1)
					(thickness 0.15)
				)
			)
		)
		(property "MPN" "04024W226MAT2A"
			(at 223.45 192.498 0)
			(layer "F.Fab")
			(hide yes)
			(effects
				(font
					(size 1 1)
					(thickness 0.15)
				)
			)
		)
		(property "Manufacturer" "AVX"
			(at 223.45 192.498 0)
			(layer "F.Fab")
			(hide yes)
			(effects
				(font
					(size 1 1)
					(thickness 0.15)
				)
			)
		)
		(property "Val" "22u"
			(at 223.45 192.498 0)
			(layer "F.Fab")
			(hide yes)
			(effects
				(font
					(size 1 1)
					(thickness 0.15)
				)
			)
		)
		(property "Voltage" ""
			(at 223.45 192.498 0)
			(layer "F.Fab")
			(hide yes)
			(effects
				(font
					(size 1 1)
					(thickness 0.15)
				)
			)
		)
		(sheetname "Supply")
		(sheetfile "supply.kicad_sch")
		(attr smd)
		(fp_rect
			(start -0.94 -0.47)
			(end 0.94 0.47)
			(stroke
				(width 0.05)
				(type solid)
			)
			(fill no)
			(layer "F.CrtYd")
		)
		(fp_rect
			(start -0.499 -0.249)
			(end 0.499 0.249)
			(stroke
				(width 0.15)
				(type solid)
			)
			(fill no)
			(layer "F.Fab")
		)
		(pad "1" smd roundrect
			(at -0.484 0 180)
			(size 0.59 0.64)
			(layers "F.Cu" "F.Mask" "F.Paste")
			(roundrect_rratio 0.25)
			(net 576 "/Supply/3V3_REG")
			(pintype "passive")
		)
		(pad "2" smd roundrect
			(at 0.484 0 180)
			(size 0.59 0.64)
			(layers "F.Cu" "F.Mask" "F.Paste")
			(roundrect_rratio 0.25)
			(net 5 "GND")
			(pintype "passive")
		)
	)
	(footprint "antmicro-footprints:C_0402_1005Metric"
		(layer "F.Cu")
		(at 127.95 86.874)
		(descr "Capacitor SMD 0402")
		(tags "capacitor SMD 0402")
		(property "Reference" "C159"
			(at -3.65 0.426 0)
			(layer "F.SilkS")
			(effects
				(font
					(size 0.7 0.7)
					(thickness 0.15)
				)
				(justify left bottom)
			)
		)
		(property "Value" "C_100n_6V3_0402"
			(at 0 1.4 0)
			(layer "F.Fab")
			(effects
				(font
					(size 0.7 0.7)
					(thickness 0.15)
				)
				(justify left bottom)
			)
		)
		(property "Description" " "
			(at 0 0 0)
			(layer "F.Fab")
			(hide yes)
			(effects
				(font
					(size 1.27 1.27)
					(thickness 0.15)
				)
			)
		)
		(property "Author" "Antmicro"
			(at 0 0 0)
			(layer "F.Fab")
			(hide yes)
			(effects
				(font
					(size 1 1)
					(thickness 0.15)
				)
			)
		)
		(property "Dielectric" ""
			(at 0 0 0)
			(layer "F.Fab")
			(hide yes)
			(effects
				(font
					(size 1 1)
					(thickness 0.15)
				)
			)
		)
		(property "License" "Apache-2.0"
			(at 0 0 0)
			(layer "F.Fab")
			(hide yes)
			(effects
				(font
					(size 1 1)
					(thickness 0.15)
				)
			)
		)
		(property "MPN" "0402X104K6R3CT"
			(at 0 0 0)
			(layer "F.Fab")
			(hide yes)
			(effects
				(font
					(size 1 1)
					(thickness 0.15)
				)
			)
		)
		(property "Manufacturer" "Walsin"
			(at 0 0 0)
			(layer "F.Fab")
			(hide yes)
			(effects
				(font
					(size 1 1)
					(thickness 0.15)
				)
			)
		)
		(property "Val" "100n"
			(at 0 0 0)
			(layer "F.Fab")
			(hide yes)
			(effects
				(font
					(size 1 1)
					(thickness 0.15)
				)
			)
		)
		(property "Voltage" ""
			(at 0 0 0)
			(layer "F.Fab")
			(hide yes)
			(effects
				(font
					(size 1 1)
					(thickness 0.15)
				)
			)
		)
		(sheetname "Supply")
		(sheetfile "supply.kicad_sch")
		(attr smd)
		(fp_rect
			(start -0.94 -0.47)
			(end 0.94 0.47)
			(stroke
				(width 0.05)
				(type solid)
			)
			(fill no)
			(layer "F.CrtYd")
		)
		(fp_rect
			(start -0.499 -0.249)
			(end 0.499 0.249)
			(stroke
				(width 0.15)
				(type solid)
			)
			(fill no)
			(layer "F.Fab")
		)
		(pad "1" smd roundrect
			(at -0.484 0)
			(size 0.59 0.64)
			(layers "F.Cu" "F.Mask" "F.Paste")
			(roundrect_rratio 0.25)
			(net 579 "/Supply/1V1_SW")
			(pintype "passive")
		)
		(pad "2" smd roundrect
			(at 0.484 0)
			(size 0.59 0.64)
			(layers "F.Cu" "F.Mask" "F.Paste")
			(roundrect_rratio 0.25)
			(net 580 "/Supply/1V1_BST")
			(pintype "passive")
		)
	)
	(footprint "antmicro-footprints:TP_SMD_1mm"
		(layer "F.Cu")
		(at 109.0992 104.4)
		(property "Reference" "TP20"
			(at -0.5992 1.2 270)
			(layer "F.SilkS")
			(effects
				(font
					(size 0.7 0.7)
					(thickness 0.15)
				)
				(justify left bottom)
			)
		)
		(property "Value" "TP_1mm_SMD"
			(at 0 1.4 0)
			(layer "F.Fab")
			(effects
				(font
					(size 0.7 0.7)
					(thickness 0.15)
				)
				(justify left bottom)
			)
		)
		(property "Description" "Test Point 1mm"
			(at 0 0 0)
			(layer "F.Fab")
			(hide yes)
			(effects
				(font
					(size 1.27 1.27)
					(thickness 0.15)
				)
			)
		)
		(property "Author" "Antmicro"
			(at 0 0 0)
			(layer "F.Fab")
			(hide yes)
			(effects
				(font
					(size 1 1)
					(thickness 0.15)
				)
			)
		)
		(property "License" "Apache-2.0"
			(at 0 0 0)
			(layer "F.Fab")
			(hide yes)
			(effects
				(font
					(size 1 1)
					(thickness 0.15)
				)
			)
		)
		(property "MPN" ""
			(at 0 0 0)
			(layer "F.Fab")
			(hide yes)
			(effects
				(font
					(size 1 1)
					(thickness 0.15)
				)
			)
		)
		(property "Manufacturer" ""
			(at 0 0 0)
			(layer "F.Fab")
			(hide yes)
			(effects
				(font
					(size 1 1)
					(thickness 0.15)
				)
			)
		)
		(sheetname "Supply")
		(sheetfile "supply.kicad_sch")
		(attr exclude_from_pos_files)
		(pad "1" smd circle
			(at 0 0)
			(size 1 1)
			(layers "F.Cu" "F.Mask")
			(net 5 "GND")
			(pinfunction "1")
			(pintype "passive")
		)
	)
	(footprint "antmicro-footprints:R_0402_1005Metric"
		(layer "F.Cu")
		(at 123.6475 100.449)
		(descr "Resistor SMD 0402")
		(tags "resistor SMD 0402")
		(property "Reference" "R127"
			(at -3.5475 0.351 0)
			(layer "F.SilkS")
			(effects
				(font
					(size 0.7 0.7)
					(thickness 0.15)
				)
				(justify left bottom)
			)
		)
		(property "Value" "R_0R_0402"
			(at 0 1.4 0)
			(layer "F.Fab")
			(effects
				(font
					(size 0.7 0.7)
					(thickness 0.15)
				)
				(justify left bottom)
			)
		)
		(property "Description" "0R resistor in 0402 package with unspecified tolerance"
			(at 0 0 0)
			(layer "F.Fab")
			(hide yes)
			(effects
				(font
					(size 1.27 1.27)
					(thickness 0.15)
				)
			)
		)
		(property "Author" "Antmicro"
			(at 0 0 0)
			(layer "F.Fab")
			(hide yes)
			(effects
				(font
					(size 1 1)
					(thickness 0.15)
				)
			)
		)
		(property "Current" "1A"
			(at 0 0 0)
			(layer "F.Fab")
			(hide yes)
			(effects
				(font
					(size 1 1)
					(thickness 0.15)
				)
			)
		)
		(property "License" "Apache-2.0"
			(at 0 0 0)
			(layer "F.Fab")
			(hide yes)
			(effects
				(font
					(size 1 1)
					(thickness 0.15)
				)
			)
		)
		(property "MPN" "ERJ2GE0R00X"
			(at 0 0 0)
			(layer "F.Fab")
			(hide yes)
			(effects
				(font
					(size 1 1)
					(thickness 0.15)
				)
			)
		)
		(property "Manufacturer" "Panasonic"
			(at 0 0 0)
			(layer "F.Fab")
			(hide yes)
			(effects
				(font
					(size 1 1)
					(thickness 0.15)
				)
			)
		)
		(property "Tolerance" ""
			(at 0 0 0)
			(layer "F.Fab")
			(hide yes)
			(effects
				(font
					(size 1 1)
					(thickness 0.15)
				)
			)
		)
		(property "Val" "0R"
			(at 0 0 0)
			(layer "F.Fab")
			(hide yes)
			(effects
				(font
					(size 1 1)
					(thickness 0.15)
				)
			)
		)
		(sheetname "Supply")
		(sheetfile "supply.kicad_sch")
		(attr smd)
		(fp_rect
			(start -0.93 -0.47)
			(end 0.93 0.47)
			(stroke
				(width 0.05)
				(type solid)
			)
			(fill no)
			(layer "F.CrtYd")
		)
		(fp_rect
			(start -0.5 -0.25)
			(end 0.5 0.25)
			(stroke
				(width 0.15)
				(type solid)
			)
			(fill no)
			(layer "F.Fab")
		)
		(pad "1" smd roundrect
			(at -0.485 0)
			(size 0.59 0.64)
			(layers "F.Cu" "F.Mask" "F.Paste")
			(roundrect_rratio 0.25)
			(net 5 "GND")
			(pintype "passive")
		)
		(pad "2" smd roundrect
			(at 0.485 0)
			(size 0.59 0.64)
			(layers "F.Cu" "F.Mask" "F.Paste")
			(roundrect_rratio 0.25)
			(net 613 "/Supply/1V0_SS{slash}TR")
			(pintype "passive")
		)
	)
	(footprint "antmicro-footprints:C_0402_1005Metric"
		(layer "F.Cu")
		(at 123.65 87.974 180)
		(descr "Capacitor SMD 0402")
		(tags "capacitor SMD 0402")
		(property "Reference" "C164"
			(at 3.65 -0.326 180)
			(layer "F.SilkS")
			(effects
				(font
					(size 0.7 0.7)
					(thickness 0.15)
				)
				(justify left bottom)
			)
		)
		(property "Value" "C_1u_0402"
			(at 0 1.4 180)
			(layer "F.Fab")
			(effects
				(font
					(size 0.7 0.7)
					(thickness 0.15)
				)
				(justify left bottom)
			)
		)
		(property "Description" " "
			(at 0 0 180)
			(layer "F.Fab")
			(hide yes)
			(effects
				(font
					(size 1.27 1.27)
					(thickness 0.15)
				)
			)
		)
		(property "Author" "Antmicro"
			(at 247.3 175.948 0)
			(layer "F.Fab")
			(hide yes)
			(effects
				(font
					(size 1 1)
					(thickness 0.15)
				)
			)
		)
		(property "Dielectric" ""
			(at 247.3 175.948 0)
			(layer "F.Fab")
			(hide yes)
			(effects
				(font
					(size 1 1)
					(thickness 0.15)
				)
			)
		)
		(property "License" "Apache-2.0"
			(at 247.3 175.948 0)
			(layer "F.Fab")
			(hide yes)
			(effects
				(font
					(size 1 1)
					(thickness 0.15)
				)
			)
		)
		(property "MPN" "C1005X6S1A105K050BC"
			(at 247.3 175.948 0)
			(layer "F.Fab")
			(hide yes)
			(effects
				(font
					(size 1 1)
					(thickness 0.15)
				)
			)
		)
		(property "Manufacturer" "TDK"
			(at 247.3 175.948 0)
			(layer "F.Fab")
			(hide yes)
			(effects
				(font
					(size 1 1)
					(thickness 0.15)
				)
			)
		)
		(property "Val" "1u"
			(at 247.3 175.948 0)
			(layer "F.Fab")
			(hide yes)
			(effects
				(font
					(size 1 1)
					(thickness 0.15)
				)
			)
		)
		(property "Voltage" ""
			(at 247.3 175.948 0)
			(layer "F.Fab")
			(hide yes)
			(effects
				(font
					(size 1 1)
					(thickness 0.15)
				)
			)
		)
		(sheetname "Supply")
		(sheetfile "supply.kicad_sch")
		(attr smd)
		(fp_rect
			(start -0.94 -0.47)
			(end 0.94 0.47)
			(stroke
				(width 0.05)
				(type solid)
			)
			(fill no)
			(layer "F.CrtYd")
		)
		(fp_rect
			(start -0.499 -0.249)
			(end 0.499 0.249)
			(stroke
				(width 0.15)
				(type solid)
			)
			(fill no)
			(layer "F.Fab")
		)
		(pad "1" smd roundrect
			(at -0.484 0 180)
			(size 0.59 0.64)
			(layers "F.Cu" "F.Mask" "F.Paste")
			(roundrect_rratio 0.25)
			(net 591 "/Supply/1V1_VCC_INT")
			(pintype "passive")
		)
		(pad "2" smd roundrect
			(at 0.484 0 180)
			(size 0.59 0.64)
			(layers "F.Cu" "F.Mask" "F.Paste")
			(roundrect_rratio 0.25)
			(net 5 "GND")
			(pintype "passive")
		)
	)
	(footprint "antmicro-footprints:C_0402_1005Metric"
		(layer "F.Cu")
		(at 126.9325 102.449 180)
		(descr "Capacitor SMD 0402")
		(tags "capacitor SMD 0402")
		(property "Reference" "C156"
			(at 1.9325 -1.251 180)
			(layer "F.SilkS")
			(effects
				(font
					(size 0.7 0.7)
					(thickness 0.15)
				)
				(justify left bottom)
			)
		)
		(property "Value" "C_10u_0402"
			(at 0 1.4 180)
			(layer "F.Fab")
			(effects
				(font
					(size 0.7 0.7)
					(thickness 0.15)
				)
				(justify left bottom)
			)
		)
		(property "Description" " "
			(at 0 0 180)
			(layer "F.Fab")
			(hide yes)
			(effects
				(font
					(size 1.27 1.27)
					(thickness 0.15)
				)
			)
		)
		(property "Author" "Antmicro"
			(at 253.865 204.898 0)
			(layer "F.Fab")
			(hide yes)
			(effects
				(font
					(size 1 1)
					(thickness 0.15)
				)
			)
		)
		(property "Dielectric" ""
			(at 253.865 204.898 0)
			(layer "F.Fab")
			(hide yes)
			(effects
				(font
					(size 1 1)
					(thickness 0.15)
				)
			)
		)
		(property "License" "Apache-2.0"
			(at 253.865 204.898 0)
			(layer "F.Fab")
			(hide yes)
			(effects
				(font
					(size 1 1)
					(thickness 0.15)
				)
			)
		)
		(property "MPN" "CC0402MRX5R5BB106"
			(at 253.865 204.898 0)
			(layer "F.Fab")
			(hide yes)
			(effects
				(font
					(size 1 1)
					(thickness 0.15)
				)
			)
		)
		(property "Manufacturer" "Yaego"
			(at 253.865 204.898 0)
			(layer "F.Fab")
			(hide yes)
			(effects
				(font
					(size 1 1)
					(thickness 0.15)
				)
			)
		)
		(property "Val" "10u"
			(at 253.865 204.898 0)
			(layer "F.Fab")
			(hide yes)
			(effects
				(font
					(size 1 1)
					(thickness 0.15)
				)
			)
		)
		(property "Voltage" ""
			(at 253.865 204.898 0)
			(layer "F.Fab")
			(hide yes)
			(effects
				(font
					(size 1 1)
					(thickness 0.15)
				)
			)
		)
		(sheetname "Supply")
		(sheetfile "supply.kicad_sch")
		(attr smd)
		(fp_rect
			(start -0.94 -0.47)
			(end 0.94 0.47)
			(stroke
				(width 0.05)
				(type solid)
			)
			(fill no)
			(layer "F.CrtYd")
		)
		(fp_rect
			(start -0.499 -0.249)
			(end 0.499 0.249)
			(stroke
				(width 0.15)
				(type solid)
			)
			(fill no)
			(layer "F.Fab")
		)
		(pad "1" smd roundrect
			(at -0.484 0 180)
			(size 0.59 0.64)
			(layers "F.Cu" "F.Mask" "F.Paste")
			(roundrect_rratio 0.25)
			(net 463 "VCC5V0_INT")
			(pintype "passive")
		)
		(pad "2" smd roundrect
			(at 0.484 0 180)
			(size 0.59 0.64)
			(layers "F.Cu" "F.Mask" "F.Paste")
			(roundrect_rratio 0.25)
			(net 5 "GND")
			(pintype "passive")
		)
	)
)
